(kicad_pcb
	(version 20260206)
	(generator "pcbnew")
	(generator_version "10.0")
	(general
		(thickness 1.6)
		(legacy_teardrops no)
	)
	(paper "A4")
	(title_block
		(title "panther-plus-userver — 13130-1b_20150205.brd")
		(comment 1 "Honey Badger (Wiwynn) / footprints 1465-1472 of 1509")
	)
	(layers
		(0 "F.Cu" signal "TOP")
		(4 "In1.Cu" signal "L2")
		(6 "In2.Cu" signal "L3")
		(8 "In3.Cu" signal "L4")
		(10 "In4.Cu" signal "L5")
		(12 "In5.Cu" signal "L6")
		(14 "In6.Cu" signal "L7")
		(16 "In7.Cu" signal "L8")
		(18 "In8.Cu" signal "L9")
		(20 "In9.Cu" signal "L10")
		(22 "In10.Cu" signal "L11")
		(2 "B.Cu" signal "BOTTOM")
		(9 "F.Adhes" user "F.Adhesive")
		(11 "B.Adhes" user "B.Adhesive")
		(13 "F.Paste" user "Package Geometry/Pastemask Top")
		(15 "B.Paste" user "Package Geometry/Pastemask Bottom")
		(5 "F.SilkS" user "Ref Des/Silkscreen Top")
		(7 "B.SilkS" user "Ref Des/Silkscreen Bottom")
		(1 "F.Mask" user "Board Geometry/Soldermask Top")
		(3 "B.Mask" user "Board Geometry/Soldermask Bottom")
		(17 "Dwgs.User" user "User.Drawings")
		(19 "Cmts.User" user "User.Comments")
		(21 "Eco1.User" user "User.Eco1")
		(23 "Eco2.User" user "User.Eco2")
		(25 "Edge.Cuts" user "Board Geometry/Outline")
		(27 "Margin" user)
		(31 "F.CrtYd" user "Package Geometry/Place Bound Top")
		(29 "B.CrtYd" user "Package Geometry/Place Bound Bottom")
		(35 "F.Fab" user "Ref Des/Assembly Top")
		(33 "B.Fab" user "Ref Des/Assembly Bottom")
	)
	(footprint ""
		(layer "B.Cu")
		(at 65.4812 -20.8026)
		(property "Reference" "R504"
			(at 0 0 0)
			(layer "B.SilkS")
			(hide yes)
			(effects
				(font
					(size 1.27 1.27)
				)
				(justify mirror)
			)
		)
		(property "Value" "4K7R2F-GP"
			(at -1.7907 -1.1176 0)
			(unlocked yes)
			(layer "B.Fab")
			(hide yes)
			(effects
				(font
					(size 1.016 1.016)
					(thickness 0.1524)
				)
				(justify mirror)
			)
		)
		(property "Device Type" "R402H16"
			(at -1.7907 -2.6416 0)
			(unlocked yes)
			(layer "B.Fab")
			(hide yes)
			(effects
				(font
					(size 1.016 1.016)
					(thickness 0.1524)
				)
				(justify mirror)
			)
		)
		(duplicate_pad_numbers_are_jumpers no)
		(fp_rect
			(start 0.381 0.8382)
			(end -0.381 -0.8382)
			(stroke
				(width 0)
				(type default)
			)
			(fill no)
			(layer "B.CrtYd")
		)
		(fp_rect
			(start 0.381 0.8382)
			(end -0.381 -0.8382)
			(stroke
				(width 0)
				(type default)
			)
			(fill no)
			(layer "B.Fab")
		)
		(pad "1" smd custom
			(at 0 -0.4318 180)
			(size 0.127 0.127)
			(layers "B.Cu" "B.Mask" "B.Paste")
			(net "MSATA_ACT#")
			(options
				(clearance outline)
				(anchor circle)
			)
			(primitives
				(gr_poly
					(pts
						(arc
							(start -0.2032 0.2794)
							(mid -0.239121 0.264521)
							(end -0.254 0.2286)
						)
						(arc
							(start -0.254 -0.2286)
							(mid -0.239121 -0.264521)
							(end -0.2032 -0.2794)
						)
						(arc
							(start 0.2032 -0.2794)
							(mid 0.239121 -0.264521)
							(end 0.254 -0.2286)
						)
						(arc
							(start 0.254 0.2286)
							(mid 0.239121 0.264521)
							(end 0.2032 0.2794)
						)
					)
					(width 0)
					(fill yes)
				)
			)
		)
		(pad "2" smd custom
			(at 0 0.4318 180)
			(size 0.127 0.127)
			(layers "B.Cu" "B.Mask" "B.Paste")
			(net "GND")
			(options
				(clearance outline)
				(anchor circle)
			)
			(primitives
				(gr_poly
					(pts
						(arc
							(start -0.2032 0.2794)
							(mid -0.239121 0.264521)
							(end -0.254 0.2286)
						)
						(arc
							(start -0.254 -0.2286)
							(mid -0.239121 -0.264521)
							(end -0.2032 -0.2794)
						)
						(arc
							(start 0.2032 -0.2794)
							(mid 0.239121 -0.264521)
							(end 0.254 -0.2286)
						)
						(arc
							(start 0.254 0.2286)
							(mid 0.239121 0.264521)
							(end 0.2032 0.2794)
						)
					)
					(width 0)
					(fill yes)
				)
			)
		)
	)
	(footprint ""
		(layer "B.Cu")
		(at 190.119 -27.94)
		(property "Reference" "PR215"
			(at 0 0 0)
			(layer "B.SilkS")
			(hide yes)
			(effects
				(font
					(size 1.27 1.27)
				)
				(justify mirror)
			)
		)
		(property "Value" "2K61R2F-1-GP"
			(at -1.7907 -1.1176 0)
			(unlocked yes)
			(layer "B.Fab")
			(hide yes)
			(effects
				(font
					(size 1.016 1.016)
					(thickness 0.1524)
				)
				(justify mirror)
			)
		)
		(property "Device Type" "R402H16"
			(at -1.7907 -2.6416 0)
			(unlocked yes)
			(layer "B.Fab")
			(hide yes)
			(effects
				(font
					(size 1.016 1.016)
					(thickness 0.1524)
				)
				(justify mirror)
			)
		)
		(duplicate_pad_numbers_are_jumpers no)
		(fp_rect
			(start 0.381 0.8382)
			(end -0.381 -0.8382)
			(stroke
				(width 0)
				(type default)
			)
			(fill no)
			(layer "B.CrtYd")
		)
		(fp_rect
			(start 0.381 0.8382)
			(end -0.381 -0.8382)
			(stroke
				(width 0)
				(type default)
			)
			(fill no)
			(layer "B.Fab")
		)
		(pad "1" smd custom
			(at 0 -0.4318 180)
			(size 0.127 0.127)
			(layers "B.Cu" "B.Mask" "B.Paste")
			(net "VR_PVDDRA_ISUMP1")
			(options
				(clearance outline)
				(anchor circle)
			)
			(primitives
				(gr_poly
					(pts
						(arc
							(start -0.2032 0.2794)
							(mid -0.239121 0.264521)
							(end -0.254 0.2286)
						)
						(arc
							(start -0.254 -0.2286)
							(mid -0.239121 -0.264521)
							(end -0.2032 -0.2794)
						)
						(arc
							(start 0.2032 -0.2794)
							(mid 0.239121 -0.264521)
							(end 0.254 -0.2286)
						)
						(arc
							(start 0.254 0.2286)
							(mid 0.239121 0.264521)
							(end 0.2032 0.2794)
						)
					)
					(width 0)
					(fill yes)
				)
			)
		)
		(pad "2" smd custom
			(at 0 0.4318 180)
			(size 0.127 0.127)
			(layers "B.Cu" "B.Mask" "B.Paste")
			(net "VR_PVDDRA_ISUMP1_R")
			(options
				(clearance outline)
				(anchor circle)
			)
			(primitives
				(gr_poly
					(pts
						(arc
							(start -0.2032 0.2794)
							(mid -0.239121 0.264521)
							(end -0.254 0.2286)
						)
						(arc
							(start -0.254 -0.2286)
							(mid -0.239121 -0.264521)
							(end -0.2032 -0.2794)
						)
						(arc
							(start 0.2032 -0.2794)
							(mid 0.239121 -0.264521)
							(end 0.254 -0.2286)
						)
						(arc
							(start 0.254 0.2286)
							(mid 0.239121 0.264521)
							(end 0.2032 0.2794)
						)
					)
					(width 0)
					(fill yes)
				)
			)
		)
	)
	(footprint ""
		(layer "B.Cu")
		(at 101.092 -64.643)
		(property "Reference" "PC8"
			(at 0 0 0)
			(layer "B.SilkS")
			(hide yes)
			(effects
				(font
					(size 1.27 1.27)
				)
				(justify mirror)
			)
		)
		(property "Value" "SC1U10V2KX-1GP"
			(at -1.1811 -2.7051 0)
			(unlocked yes)
			(layer "B.Fab")
			(hide yes)
			(effects
				(font
					(size 1.016 1.016)
					(thickness 0.1524)
				)
				(justify mirror)
			)
		)
		(property "Device Type" "C402H22"
			(at -1.1811 -4.2291 0)
			(unlocked yes)
			(layer "B.Fab")
			(hide yes)
			(effects
				(font
					(size 1.016 1.016)
					(thickness 0.1524)
				)
				(justify mirror)
			)
		)
		(duplicate_pad_numbers_are_jumpers no)
		(fp_rect
			(start 0.381 0.7366)
			(end -0.381 -0.7366)
			(stroke
				(width 0)
				(type default)
			)
			(fill no)
			(layer "B.CrtYd")
		)
		(fp_rect
			(start 0.381 0.7366)
			(end -0.381 -0.7366)
			(stroke
				(width 0)
				(type default)
			)
			(fill no)
			(layer "B.Fab")
		)
		(pad "1" smd custom
			(at 0 -0.4572 180)
			(size 0.1143 0.1143)
			(layers "B.Cu" "B.Mask" "B.Paste")
			(net "AGND_P1V1")
			(options
				(clearance outline)
				(anchor circle)
			)
			(primitives
				(gr_poly
					(pts
						(arc
							(start -0.254 0.1778)
							(mid -0.239121 0.213721)
							(end -0.2032 0.2286)
						)
						(arc
							(start 0.2032 0.2286)
							(mid 0.239121 0.213721)
							(end 0.254 0.1778)
						)
						(arc
							(start 0.254 -0.1778)
							(mid 0.239121 -0.213721)
							(end 0.2032 -0.2286)
						)
						(arc
							(start -0.2032 -0.2286)
							(mid -0.239121 -0.213721)
							(end -0.254 -0.1778)
						)
					)
					(width 0)
					(fill yes)
				)
			)
		)
		(pad "2" smd custom
			(at 0 0.4572 180)
			(size 0.1143 0.1143)
			(layers "B.Cu" "B.Mask" "B.Paste")
			(net "VR_P1V1_AVIN")
			(options
				(clearance outline)
				(anchor circle)
			)
			(primitives
				(gr_poly
					(pts
						(arc
							(start -0.254 0.1778)
							(mid -0.239121 0.213721)
							(end -0.2032 0.2286)
						)
						(arc
							(start 0.2032 0.2286)
							(mid 0.239121 0.213721)
							(end 0.254 0.1778)
						)
						(arc
							(start 0.254 -0.1778)
							(mid 0.239121 -0.213721)
							(end 0.2032 -0.2286)
						)
						(arc
							(start -0.2032 -0.2286)
							(mid -0.239121 -0.213721)
							(end -0.254 -0.1778)
						)
					)
					(width 0)
					(fill yes)
				)
			)
		)
	)
	(footprint ""
		(layer "B.Cu")
		(at 81.026 -65.786)
		(property "Reference" "R289"
			(at 0 0 0)
			(layer "B.SilkS")
			(hide yes)
			(effects
				(font
					(size 1.27 1.27)
				)
				(justify mirror)
			)
		)
		(property "Value" "100R2F-L1-GP-U"
			(at -0.064008 -3.993896 0)
			(unlocked yes)
			(layer "B.Fab")
			(hide yes)
			(effects
				(font
					(size 1.016 1.016)
					(thickness 0.1524)
				)
				(justify mirror)
			)
		)
		(property "Device Type" "R402H14"
			(at -0.064008 -5.517896 0)
			(unlocked yes)
			(layer "B.Fab")
			(hide yes)
			(effects
				(font
					(size 1.016 1.016)
					(thickness 0.1524)
				)
				(justify mirror)
			)
		)
		(duplicate_pad_numbers_are_jumpers no)
		(fp_rect
			(start 0.381 0.8382)
			(end -0.381 -0.8382)
			(stroke
				(width 0)
				(type default)
			)
			(fill no)
			(layer "B.CrtYd")
		)
		(fp_rect
			(start 0.381 0.8382)
			(end -0.381 -0.8382)
			(stroke
				(width 0)
				(type default)
			)
			(fill no)
			(layer "B.Fab")
		)
		(pad "1" smd custom
			(at 0 -0.4318 180)
			(size 0.127 0.127)
			(layers "B.Cu" "B.Mask" "B.Paste")
			(net "P1V0")
			(options
				(clearance outline)
				(anchor circle)
			)
			(primitives
				(gr_poly
					(pts
						(arc
							(start -0.2032 0.2794)
							(mid -0.239121 0.264521)
							(end -0.254 0.2286)
						)
						(arc
							(start -0.254 -0.2286)
							(mid -0.239121 -0.264521)
							(end -0.2032 -0.2794)
						)
						(arc
							(start 0.2032 -0.2794)
							(mid 0.239121 -0.264521)
							(end 0.254 -0.2286)
						)
						(arc
							(start 0.254 0.2286)
							(mid 0.239121 0.264521)
							(end 0.2032 0.2794)
						)
					)
					(width 0)
					(fill yes)
				)
			)
		)
		(pad "2" smd custom
			(at 0 0.4318 180)
			(size 0.127 0.127)
			(layers "B.Cu" "B.Mask" "B.Paste")
			(net "SVID_CPU_DATA")
			(options
				(clearance outline)
				(anchor circle)
			)
			(primitives
				(gr_poly
					(pts
						(arc
							(start -0.2032 0.2794)
							(mid -0.239121 0.264521)
							(end -0.254 0.2286)
						)
						(arc
							(start -0.254 -0.2286)
							(mid -0.239121 -0.264521)
							(end -0.2032 -0.2794)
						)
						(arc
							(start 0.2032 -0.2794)
							(mid 0.239121 -0.264521)
							(end 0.254 -0.2286)
						)
						(arc
							(start 0.254 0.2286)
							(mid 0.239121 0.264521)
							(end 0.2032 0.2794)
						)
					)
					(width 0)
					(fill yes)
				)
			)
		)
	)
	(footprint ""
		(layer "B.Cu")
		(at 119.888 -65.151 180)
		(property "Reference" "R499"
			(at 0 0 0)
			(layer "B.SilkS")
			(hide yes)
			(effects
				(font
					(size 1.27 1.27)
				)
				(justify mirror)
			)
		)
		(property "Value" "4K7R2F-GP"
			(at -1.7907 -1.1176 180)
			(unlocked yes)
			(layer "B.Fab")
			(hide yes)
			(effects
				(font
					(size 1.016 1.016)
					(thickness 0.1524)
				)
				(justify mirror)
			)
		)
		(property "Device Type" "R402H16"
			(at -1.7907 -2.6416 180)
			(unlocked yes)
			(layer "B.Fab")
			(hide yes)
			(effects
				(font
					(size 1.016 1.016)
					(thickness 0.1524)
				)
				(justify mirror)
			)
		)
		(duplicate_pad_numbers_are_jumpers no)
		(fp_rect
			(start 0.381 0.8382)
			(end -0.381 -0.8382)
			(stroke
				(width 0)
				(type default)
			)
			(fill no)
			(layer "B.CrtYd")
		)
		(fp_rect
			(start 0.381 0.8382)
			(end -0.381 -0.8382)
			(stroke
				(width 0)
				(type default)
			)
			(fill no)
			(layer "B.Fab")
		)
		(pad "1" smd custom
			(at 0 -0.4318)
			(size 0.127 0.127)
			(layers "B.Cu" "B.Mask" "B.Paste")
			(net "P3V3_STBY")
			(options
				(clearance outline)
				(anchor circle)
			)
			(primitives
				(gr_poly
					(pts
						(arc
							(start -0.2032 0.2794)
							(mid -0.239121 0.264521)
							(end -0.254 0.2286)
						)
						(arc
							(start -0.254 -0.2286)
							(mid -0.239121 -0.264521)
							(end -0.2032 -0.2794)
						)
						(arc
							(start 0.2032 -0.2794)
							(mid 0.239121 -0.264521)
							(end 0.254 -0.2286)
						)
						(arc
							(start 0.254 0.2286)
							(mid 0.239121 0.264521)
							(end 0.2032 0.2794)
						)
					)
					(width 0)
					(fill yes)
				)
			)
		)
		(pad "2" smd custom
			(at 0 0.4318)
			(size 0.127 0.127)
			(layers "B.Cu" "B.Mask" "B.Paste")
			(net "SMB_HOST_LV_DATA")
			(options
				(clearance outline)
				(anchor circle)
			)
			(primitives
				(gr_poly
					(pts
						(arc
							(start -0.2032 0.2794)
							(mid -0.239121 0.264521)
							(end -0.254 0.2286)
						)
						(arc
							(start -0.254 -0.2286)
							(mid -0.239121 -0.264521)
							(end -0.2032 -0.2794)
						)
						(arc
							(start 0.2032 -0.2794)
							(mid 0.239121 -0.264521)
							(end 0.254 -0.2286)
						)
						(arc
							(start 0.254 0.2286)
							(mid 0.239121 0.264521)
							(end 0.2032 0.2794)
						)
					)
					(width 0)
					(fill yes)
				)
			)
		)
	)
	(footprint ""
		(layer "B.Cu")
		(at 27.305 -64.77 -90)
		(property "Reference" "R496"
			(at 0 0 90)
			(layer "B.SilkS")
			(hide yes)
			(effects
				(font
					(size 1.27 1.27)
				)
				(justify mirror)
			)
		)
		(property "Value" "10KR2F-2-GP"
			(at -1.7907 -1.1176 270)
			(unlocked yes)
			(layer "B.Fab")
			(hide yes)
			(effects
				(font
					(size 1.016 1.016)
					(thickness 0.1524)
				)
				(justify mirror)
			)
		)
		(property "Device Type" "R402H16"
			(at -1.7907 -2.6416 270)
			(unlocked yes)
			(layer "B.Fab")
			(hide yes)
			(effects
				(font
					(size 1.016 1.016)
					(thickness 0.1524)
				)
				(justify mirror)
			)
		)
		(duplicate_pad_numbers_are_jumpers no)
		(fp_rect
			(start 0.381 0.8382)
			(end -0.381 -0.8382)
			(stroke
				(width 0)
				(type default)
			)
			(fill no)
			(layer "B.CrtYd")
		)
		(fp_rect
			(start 0.381 0.8382)
			(end -0.381 -0.8382)
			(stroke
				(width 0)
				(type default)
			)
			(fill no)
			(layer "B.Fab")
		)
		(pad "1" smd custom
			(at 0 -0.4318 90)
			(size 0.127 0.127)
			(layers "B.Cu" "B.Mask" "B.Paste")
			(net "VCCP_5VBIAS")
			(options
				(clearance outline)
				(anchor circle)
			)
			(primitives
				(gr_poly
					(pts
						(arc
							(start -0.2032 0.2794)
							(mid -0.239121 0.264521)
							(end -0.254 0.2286)
						)
						(arc
							(start -0.254 -0.2286)
							(mid -0.239121 -0.264521)
							(end -0.2032 -0.2794)
						)
						(arc
							(start 0.2032 -0.2794)
							(mid 0.239121 -0.264521)
							(end 0.254 -0.2286)
						)
						(arc
							(start 0.254 0.2286)
							(mid 0.239121 0.264521)
							(end 0.2032 0.2794)
						)
					)
					(width 0)
					(fill yes)
				)
			)
		)
		(pad "2" smd custom
			(at 0 0.4318 90)
			(size 0.127 0.127)
			(layers "B.Cu" "B.Mask" "B.Paste")
			(net "GND")
			(options
				(clearance outline)
				(anchor circle)
			)
			(primitives
				(gr_poly
					(pts
						(arc
							(start -0.2032 0.2794)
							(mid -0.239121 0.264521)
							(end -0.254 0.2286)
						)
						(arc
							(start -0.254 -0.2286)
							(mid -0.239121 -0.264521)
							(end -0.2032 -0.2794)
						)
						(arc
							(start 0.2032 -0.2794)
							(mid 0.239121 -0.264521)
							(end 0.254 -0.2286)
						)
						(arc
							(start 0.254 0.2286)
							(mid 0.239121 0.264521)
							(end 0.2032 0.2794)
						)
					)
					(width 0)
					(fill yes)
				)
			)
		)
	)
	(footprint ""
		(layer "B.Cu")
		(at 94.361 -48.0314 180)
		(property "Reference" "C133"
			(at 0 0 0)
			(layer "B.SilkS")
			(hide yes)
			(effects
				(font
					(size 1.27 1.27)
				)
				(justify mirror)
			)
		)
		(property "Value" "SC1U10V2KX-1GP"
			(at -1.1811 -2.7051 180)
			(unlocked yes)
			(layer "B.Fab")
			(hide yes)
			(effects
				(font
					(size 1.016 1.016)
					(thickness 0.1524)
				)
				(justify mirror)
			)
		)
		(property "Device Type" "C402H22"
			(at -1.1811 -4.2291 180)
			(unlocked yes)
			(layer "B.Fab")
			(hide yes)
			(effects
				(font
					(size 1.016 1.016)
					(thickness 0.1524)
				)
				(justify mirror)
			)
		)
		(duplicate_pad_numbers_are_jumpers no)
		(fp_rect
			(start 0.381 0.7366)
			(end -0.381 -0.7366)
			(stroke
				(width 0)
				(type default)
			)
			(fill no)
			(layer "B.CrtYd")
		)
		(fp_rect
			(start 0.381 0.7366)
			(end -0.381 -0.7366)
			(stroke
				(width 0)
				(type default)
			)
			(fill no)
			(layer "B.Fab")
		)
		(pad "1" smd custom
			(at 0 -0.4572)
			(size 0.1143 0.1143)
			(layers "B.Cu" "B.Mask" "B.Paste")
			(net "P1V0")
			(options
				(clearance outline)
				(anchor circle)
			)
			(primitives
				(gr_poly
					(pts
						(arc
							(start -0.254 0.1778)
							(mid -0.239121 0.213721)
							(end -0.2032 0.2286)
						)
						(arc
							(start 0.2032 0.2286)
							(mid 0.239121 0.213721)
							(end 0.254 0.1778)
						)
						(arc
							(start 0.254 -0.1778)
							(mid 0.239121 -0.213721)
							(end 0.2032 -0.2286)
						)
						(arc
							(start -0.2032 -0.2286)
							(mid -0.239121 -0.213721)
							(end -0.254 -0.1778)
						)
					)
					(width 0)
					(fill yes)
				)
			)
		)
		(pad "2" smd custom
			(at 0 0.4572)
			(size 0.1143 0.1143)
			(layers "B.Cu" "B.Mask" "B.Paste")
			(net "GND")
			(options
				(clearance outline)
				(anchor circle)
			)
			(primitives
				(gr_poly
					(pts
						(arc
							(start -0.254 0.1778)
							(mid -0.239121 0.213721)
							(end -0.2032 0.2286)
						)
						(arc
							(start 0.2032 0.2286)
							(mid 0.239121 0.213721)
							(end 0.254 0.1778)
						)
						(arc
							(start 0.254 -0.1778)
							(mid 0.239121 -0.213721)
							(end 0.2032 -0.2286)
						)
						(arc
							(start -0.2032 -0.2286)
							(mid -0.239121 -0.213721)
							(end -0.254 -0.1778)
						)
					)
					(width 0)
					(fill yes)
				)
			)
		)
	)
	(footprint ""
		(layer "B.Cu")
		(at 100.584 -53.086 180)
		(property "Reference" "R261"
			(at 0 0 0)
			(layer "B.SilkS")
			(hide yes)
			(effects
				(font
					(size 1.27 1.27)
				)
				(justify mirror)
			)
		)
		(property "Value" "100KR2F-L1-GP"
			(at -0.064008 -3.993896 180)
			(unlocked yes)
			(layer "B.Fab")
			(hide yes)
			(effects
				(font
					(size 1.016 1.016)
					(thickness 0.1524)
				)
				(justify mirror)
			)
		)
		(property "Device Type" "R402H16"
			(at -0.064008 -5.517896 180)
			(unlocked yes)
			(layer "B.Fab")
			(hide yes)
			(effects
				(font
					(size 1.016 1.016)
					(thickness 0.1524)
				)
				(justify mirror)
			)
		)
		(duplicate_pad_numbers_are_jumpers no)
		(fp_rect
			(start 0.381 0.8382)
			(end -0.381 -0.8382)
			(stroke
				(width 0)
				(type default)
			)
			(fill no)
			(layer "B.CrtYd")
		)
		(fp_rect
			(start 0.381 0.8382)
			(end -0.381 -0.8382)
			(stroke
				(width 0)
				(type default)
			)
			(fill no)
			(layer "B.Fab")
		)
		(pad "1" smd custom
			(at 0 -0.4318)
			(size 0.127 0.127)
			(layers "B.Cu" "B.Mask" "B.Paste")
			(net "GND")
			(options
				(clearance outline)
				(anchor circle)
			)
			(primitives
				(gr_poly
					(pts
						(arc
							(start -0.2032 0.2794)
							(mid -0.239121 0.264521)
							(end -0.254 0.2286)
						)
						(arc
							(start -0.254 -0.2286)
							(mid -0.239121 -0.264521)
							(end -0.2032 -0.2794)
						)
						(arc
							(start 0.2032 -0.2794)
							(mid 0.239121 -0.264521)
							(end 0.254 -0.2286)
						)
						(arc
							(start 0.254 0.2286)
							(mid 0.239121 0.264521)
							(end 0.2032 0.2794)
						)
					)
					(width 0)
					(fill yes)
				)
			)
		)
		(pad "2" smd custom
			(at 0 0.4318)
			(size 0.127 0.127)
			(layers "B.Cu" "B.Mask" "B.Paste")
			(net "M_A_R_RESET#")
			(options
				(clearance outline)
				(anchor circle)
			)
			(primitives
				(gr_poly
					(pts
						(arc
							(start -0.2032 0.2794)
							(mid -0.239121 0.264521)
							(end -0.254 0.2286)
						)
						(arc
							(start -0.254 -0.2286)
							(mid -0.239121 -0.264521)
							(end -0.2032 -0.2794)
						)
						(arc
							(start 0.2032 -0.2794)
							(mid 0.239121 -0.264521)
							(end 0.254 -0.2286)
						)
						(arc
							(start 0.254 0.2286)
							(mid 0.239121 0.264521)
							(end 0.2032 0.2794)
						)
					)
					(width 0)
					(fill yes)
				)
			)
		)
	)
)
